(kicad_pcb
	(version 20260206)
	(generator "pcbnew")
	(generator_version "10.0")
	(general
		(thickness 1.6)
		(legacy_teardrops no)
	)
	(paper "A4")
	(title_block
		(title "baseboard — 13948-1b.1110WZS1818.brd")
		(comment 1 "Honey Badger (Wiwynn) / footprints 1247-1253 of 2523")
	)
	(layers
		(0 "F.Cu" signal "TOP")
		(4 "In1.Cu" signal "L2GND")
		(6 "In2.Cu" signal "L3")
		(8 "In3.Cu" signal "L4VCC")
		(10 "In4.Cu" signal "L5VCC")
		(12 "In5.Cu" signal "L6")
		(14 "In6.Cu" signal "L7GND")
		(2 "B.Cu" signal "BOTTOM")
		(9 "F.Adhes" user "F.Adhesive")
		(11 "B.Adhes" user "B.Adhesive")
		(13 "F.Paste" user "Package Geometry/Pastemask Top")
		(15 "B.Paste" user "Package Geometry/Pastemask Bottom")
		(5 "F.SilkS" user "Ref Des/Silkscreen Top")
		(7 "B.SilkS" user "Ref Des/Silkscreen Bottom")
		(1 "F.Mask" user "Board Geometry/Soldermask Top")
		(3 "B.Mask" user "Board Geometry/Soldermask Bottom")
		(17 "Dwgs.User" user "User.Drawings")
		(19 "Cmts.User" user "User.Comments")
		(21 "Eco1.User" user "User.Eco1")
		(23 "Eco2.User" user "User.Eco2")
		(25 "Edge.Cuts" user "Board Geometry/Outline")
		(27 "Margin" user)
		(31 "F.CrtYd" user "Package Geometry/Place Bound Top")
		(29 "B.CrtYd" user "Package Geometry/Place Bound Bottom")
		(35 "F.Fab" user "Ref Des/Assembly Top")
		(33 "B.Fab" user "Ref Des/Assembly Bottom")
	)
	(footprint ""
		(layer "F.Cu")
		(at 38.989 -170.815 180)
		(property "Reference" "SR1274"
			(at 0 0 180)
			(layer "F.SilkS")
			(hide yes)
			(effects
				(font
					(size 1.27 1.27)
				)
			)
		)
		(property "Value" "4K7R2F-GP"
			(at 0.064008 -3.993896 180)
			(unlocked yes)
			(layer "F.Fab")
			(hide yes)
			(effects
				(font
					(size 1.016 1.016)
					(thickness 0.1524)
				)
			)
		)
		(property "Device Type" "R402H16"
			(at 0.064008 -5.517896 180)
			(unlocked yes)
			(layer "F.Fab")
			(hide yes)
			(effects
				(font
					(size 1.016 1.016)
					(thickness 0.1524)
				)
			)
		)
		(duplicate_pad_numbers_are_jumpers no)
		(fp_line
			(start 0.508 -0.9398)
			(end -0.508 -0.9398)
			(stroke
				(width 0.1524)
				(type default)
			)
			(layer "F.SilkS")
		)
		(fp_line
			(start -0.508 -0.9398)
			(end -0.508 0.9398)
			(stroke
				(width 0.1524)
				(type default)
			)
			(layer "F.SilkS")
		)
		(fp_rect
			(start -0.508 0.9398)
			(end 0.508 -0.9398)
			(stroke
				(width 0)
				(type default)
			)
			(fill no)
			(layer "F.CrtYd")
		)
		(fp_rect
			(start -0.508 0.9398)
			(end 0.508 -0.9398)
			(stroke
				(width 0)
				(type default)
			)
			(fill no)
			(layer "F.Fab")
		)
		(pad "1" smd custom
			(at 0 -0.4445 180)
			(size 0.1397 0.1397)
			(layers "F.Cu" "F.Mask" "F.Paste")
			(net "P3V3_STBY")
			(options
				(clearance outline)
				(anchor circle)
			)
			(primitives
				(gr_poly
					(pts
						(arc
							(start -0.1778 -0.2794)
							(mid -0.249642 -0.249642)
							(end -0.2794 -0.1778)
						)
						(arc
							(start -0.2794 0.1778)
							(mid -0.249642 0.249642)
							(end -0.1778 0.2794)
						)
						(arc
							(start 0.1778 0.2794)
							(mid 0.249642 0.249642)
							(end 0.2794 0.1778)
						)
						(arc
							(start 0.2794 -0.1778)
							(mid 0.249642 -0.249642)
							(end 0.1778 -0.2794)
						)
					)
					(width 0)
					(fill yes)
				)
			)
		)
		(pad "2" smd custom
			(at 0 0.4445 180)
			(size 0.1397 0.1397)
			(layers "F.Cu" "F.Mask" "F.Paste")
			(net "P3V3_STBY_R7")
			(options
				(clearance outline)
				(anchor circle)
			)
			(primitives
				(gr_poly
					(pts
						(arc
							(start -0.1778 -0.2794)
							(mid -0.249642 -0.249642)
							(end -0.2794 -0.1778)
						)
						(arc
							(start -0.2794 0.1778)
							(mid -0.249642 0.249642)
							(end -0.1778 0.2794)
						)
						(arc
							(start 0.1778 0.2794)
							(mid 0.249642 0.249642)
							(end 0.2794 0.1778)
						)
						(arc
							(start 0.2794 -0.1778)
							(mid 0.249642 -0.249642)
							(end 0.1778 -0.2794)
						)
					)
					(width 0)
					(fill yes)
				)
			)
		)
	)
	(footprint ""
		(layer "F.Cu")
		(at 242.1763 -111.6838 180)
		(property "Reference" "SR933"
			(at 0 0 180)
			(layer "F.SilkS")
			(hide yes)
			(effects
				(font
					(size 1.27 1.27)
				)
			)
		)
		(property "Value" "0R2J-2-GP"
			(at 0.064008 -3.993896 180)
			(unlocked yes)
			(layer "F.Fab")
			(hide yes)
			(effects
				(font
					(size 1.016 1.016)
					(thickness 0.1524)
				)
			)
		)
		(property "Device Type" "R402H16"
			(at 0.064008 -5.517896 180)
			(unlocked yes)
			(layer "F.Fab")
			(hide yes)
			(effects
				(font
					(size 1.016 1.016)
					(thickness 0.1524)
				)
			)
		)
		(duplicate_pad_numbers_are_jumpers no)
		(fp_line
			(start 0.508 -0.9398)
			(end -0.508 -0.9398)
			(stroke
				(width 0.1524)
				(type default)
			)
			(layer "F.SilkS")
		)
		(fp_line
			(start -0.508 -0.9398)
			(end -0.508 0.9398)
			(stroke
				(width 0.1524)
				(type default)
			)
			(layer "F.SilkS")
		)
		(fp_rect
			(start -0.508 0.9398)
			(end 0.508 -0.9398)
			(stroke
				(width 0)
				(type default)
			)
			(fill no)
			(layer "F.CrtYd")
		)
		(fp_rect
			(start -0.508 0.9398)
			(end 0.508 -0.9398)
			(stroke
				(width 0)
				(type default)
			)
			(fill no)
			(layer "F.Fab")
		)
		(pad "1" smd custom
			(at 0 -0.4445 180)
			(size 0.1397 0.1397)
			(layers "F.Cu" "F.Mask" "F.Paste")
			(net "EXP_SMART_TX")
			(options
				(clearance outline)
				(anchor circle)
			)
			(primitives
				(gr_poly
					(pts
						(arc
							(start -0.1778 -0.2794)
							(mid -0.249642 -0.249642)
							(end -0.2794 -0.1778)
						)
						(arc
							(start -0.2794 0.1778)
							(mid -0.249642 0.249642)
							(end -0.1778 0.2794)
						)
						(arc
							(start 0.1778 0.2794)
							(mid 0.249642 0.249642)
							(end 0.2794 0.1778)
						)
						(arc
							(start 0.2794 -0.1778)
							(mid 0.249642 -0.249642)
							(end 0.1778 -0.2794)
						)
					)
					(width 0)
					(fill yes)
				)
			)
		)
		(pad "2" smd custom
			(at 0 0.4445 180)
			(size 0.1397 0.1397)
			(layers "F.Cu" "F.Mask" "F.Paste")
			(net "EXP_SMART_TX_R")
			(options
				(clearance outline)
				(anchor circle)
			)
			(primitives
				(gr_poly
					(pts
						(arc
							(start -0.1778 -0.2794)
							(mid -0.249642 -0.249642)
							(end -0.2794 -0.1778)
						)
						(arc
							(start -0.2794 0.1778)
							(mid -0.249642 0.249642)
							(end -0.1778 0.2794)
						)
						(arc
							(start 0.1778 0.2794)
							(mid 0.249642 0.249642)
							(end 0.2794 0.1778)
						)
						(arc
							(start 0.2794 -0.1778)
							(mid 0.249642 -0.249642)
							(end 0.1778 -0.2794)
						)
					)
					(width 0)
					(fill yes)
				)
			)
		)
	)
	(footprint ""
		(layer "F.Cu")
		(at 265.049 -16.383 180)
		(property "Reference" "TC12"
			(at 0 0 180)
			(layer "F.SilkS")
			(hide yes)
			(effects
				(font
					(size 1.27 1.27)
				)
			)
		)
		(property "Value" "SC47U16V0MX-GP"
			(at -0.00254 -4.78536 180)
			(unlocked yes)
			(layer "F.Fab")
			(hide yes)
			(effects
				(font
					(size 1.016 1.016)
					(thickness 0.1524)
				)
			)
		)
		(property "Device Type" "C1210H107"
			(at -0.00254 -6.38048 180)
			(unlocked yes)
			(layer "F.Fab")
			(hide yes)
			(effects
				(font
					(size 1.016 1.016)
					(thickness 0.1524)
				)
			)
		)
		(duplicate_pad_numbers_are_jumpers no)
		(fp_line
			(start 1.5748 2.3368)
			(end 1.5748 0.762)
			(stroke
				(width 0.1524)
				(type default)
			)
			(layer "F.SilkS")
		)
		(fp_line
			(start 1.5748 -0.762)
			(end 1.5748 -2.3368)
			(stroke
				(width 0.1524)
				(type default)
			)
			(layer "F.SilkS")
		)
		(fp_line
			(start 1.5748 -2.3368)
			(end -1.5748 -2.3368)
			(stroke
				(width 0.1524)
				(type default)
			)
			(layer "F.SilkS")
		)
		(fp_line
			(start -1.5748 2.3368)
			(end 1.5748 2.3368)
			(stroke
				(width 0.1524)
				(type default)
			)
			(layer "F.SilkS")
		)
		(fp_line
			(start -1.5748 0.762)
			(end -1.5748 2.3368)
			(stroke
				(width 0.1524)
				(type default)
			)
			(layer "F.SilkS")
		)
		(fp_line
			(start -1.5748 -2.3368)
			(end -1.5748 -0.762)
			(stroke
				(width 0.1524)
				(type default)
			)
			(layer "F.SilkS")
		)
		(fp_rect
			(start -1.651 2.413)
			(end 1.651 -2.413)
			(stroke
				(width 0)
				(type default)
			)
			(fill no)
			(layer "F.CrtYd")
		)
		(fp_poly
			(pts
				(xy 1.651 2.413) (xy 1.651 -2.413) (xy -1.651 -2.413) (xy -1.651 2.413)
			)
			(stroke
				(width 0)
				(type default)
			)
			(fill no)
			(layer "F.Fab")
		)
		(pad "1" smd rect
			(at 0 -1.4732 180)
			(size 2.794 1.397)
			(layers "F.Cu" "F.Mask" "F.Paste")
			(net "P5V_USB")
		)
		(pad "2" smd rect
			(at 0 1.4732 180)
			(size 2.794 1.397)
			(layers "F.Cu" "F.Mask" "F.Paste")
			(net "GND")
		)
	)
	(footprint ""
		(layer "F.Cu")
		(at 189.665864 -31.695136 180)
		(property "Reference" "C225"
			(at 0 0 180)
			(layer "F.SilkS")
			(hide yes)
			(effects
				(font
					(size 1.27 1.27)
				)
			)
		)
		(property "Value" "SCD1U16V2KX-3GP"
			(at 1.1811 -2.7051 180)
			(unlocked yes)
			(layer "F.Fab")
			(hide yes)
			(effects
				(font
					(size 1.016 1.016)
					(thickness 0.1524)
				)
			)
		)
		(property "Device Type" "C402H22"
			(at 1.1811 -4.2291 180)
			(unlocked yes)
			(layer "F.Fab")
			(hide yes)
			(effects
				(font
					(size 1.016 1.016)
					(thickness 0.1524)
				)
			)
		)
		(duplicate_pad_numbers_are_jumpers no)
		(fp_rect
			(start -0.4318 0.9525)
			(end 0.4318 -0.9525)
			(stroke
				(width 0)
				(type default)
			)
			(fill no)
			(layer "F.CrtYd")
		)
		(fp_rect
			(start -0.4318 0.9525)
			(end 0.4318 -0.9525)
			(stroke
				(width 0)
				(type default)
			)
			(fill no)
			(layer "F.Fab")
		)
		(pad "1" smd custom
			(at 0 -0.4445 180)
			(size 0.1524 0.1524)
			(layers "F.Cu" "F.Mask" "F.Paste")
			(net "PHY_DVDD")
			(options
				(clearance outline)
				(anchor circle)
			)
			(primitives
				(gr_poly
					(pts
						(arc
							(start 0.3048 -0.2032)
							(mid 0.275042 -0.275042)
							(end 0.2032 -0.3048)
						)
						(arc
							(start -0.2032 -0.3048)
							(mid -0.275042 -0.275042)
							(end -0.3048 -0.2032)
						)
						(arc
							(start -0.3048 0.2032)
							(mid -0.275042 0.275042)
							(end -0.2032 0.3048)
						)
						(arc
							(start 0.2032 0.3048)
							(mid 0.275042 0.275042)
							(end 0.3048 0.2032)
						)
					)
					(width 0)
					(fill yes)
				)
			)
		)
		(pad "2" smd custom
			(at 0 0.4445 180)
			(size 0.1524 0.1524)
			(layers "F.Cu" "F.Mask" "F.Paste")
			(net "GND")
			(options
				(clearance outline)
				(anchor circle)
			)
			(primitives
				(gr_poly
					(pts
						(arc
							(start 0.3048 -0.2032)
							(mid 0.275042 -0.275042)
							(end 0.2032 -0.3048)
						)
						(arc
							(start -0.2032 -0.3048)
							(mid -0.275042 -0.275042)
							(end -0.3048 -0.2032)
						)
						(arc
							(start -0.3048 0.2032)
							(mid -0.275042 0.275042)
							(end -0.2032 0.3048)
						)
						(arc
							(start 0.2032 0.3048)
							(mid 0.275042 0.275042)
							(end 0.3048 0.2032)
						)
					)
					(width 0)
					(fill yes)
				)
			)
		)
	)
	(footprint ""
		(layer "F.Cu")
		(at 348.390718 -150.853648 90)
		(property "Reference" "C167"
			(at 0 0 90)
			(layer "F.SilkS")
			(hide yes)
			(effects
				(font
					(size 1.27 1.27)
				)
			)
		)
		(property "Value" "SC1U10V2KX-4-GP"
			(at 1.1811 -2.7051 90)
			(unlocked yes)
			(layer "F.Fab")
			(hide yes)
			(effects
				(font
					(size 1.016 1.016)
					(thickness 0.1524)
				)
			)
		)
		(property "Device Type" "C402H22"
			(at 1.1811 -4.2291 90)
			(unlocked yes)
			(layer "F.Fab")
			(hide yes)
			(effects
				(font
					(size 1.016 1.016)
					(thickness 0.1524)
				)
			)
		)
		(duplicate_pad_numbers_are_jumpers no)
		(fp_rect
			(start -0.4318 0.9525)
			(end 0.4318 -0.9525)
			(stroke
				(width 0)
				(type default)
			)
			(fill no)
			(layer "F.CrtYd")
		)
		(fp_rect
			(start -0.4318 0.9525)
			(end 0.4318 -0.9525)
			(stroke
				(width 0)
				(type default)
			)
			(fill no)
			(layer "F.Fab")
		)
		(pad "1" smd custom
			(at 0 -0.4445 90)
			(size 0.1524 0.1524)
			(layers "F.Cu" "F.Mask" "F.Paste")
			(net "P3V3_STBY")
			(options
				(clearance outline)
				(anchor circle)
			)
			(primitives
				(gr_poly
					(pts
						(arc
							(start 0.3048 -0.2032)
							(mid 0.275042 -0.275042)
							(end 0.2032 -0.3048)
						)
						(arc
							(start -0.2032 -0.3048)
							(mid -0.275042 -0.275042)
							(end -0.3048 -0.2032)
						)
						(arc
							(start -0.3048 0.2032)
							(mid -0.275042 0.275042)
							(end -0.2032 0.3048)
						)
						(arc
							(start 0.2032 0.3048)
							(mid 0.275042 0.275042)
							(end 0.3048 0.2032)
						)
					)
					(width 0)
					(fill yes)
				)
			)
		)
		(pad "2" smd custom
			(at 0 0.4445 90)
			(size 0.1524 0.1524)
			(layers "F.Cu" "F.Mask" "F.Paste")
			(net "GND")
			(options
				(clearance outline)
				(anchor circle)
			)
			(primitives
				(gr_poly
					(pts
						(arc
							(start 0.3048 -0.2032)
							(mid 0.275042 -0.275042)
							(end 0.2032 -0.3048)
						)
						(arc
							(start -0.2032 -0.3048)
							(mid -0.275042 -0.275042)
							(end -0.3048 -0.2032)
						)
						(arc
							(start -0.3048 0.2032)
							(mid -0.275042 0.275042)
							(end -0.2032 0.3048)
						)
						(arc
							(start 0.2032 0.3048)
							(mid 0.275042 0.275042)
							(end 0.3048 0.2032)
						)
					)
					(width 0)
					(fill yes)
				)
			)
		)
	)
	(footprint ""
		(layer "F.Cu")
		(at 78.613 -22.86)
		(property "Reference" "PC220"
			(at 0 0 0)
			(layer "F.SilkS")
			(hide yes)
			(effects
				(font
					(size 1.27 1.27)
				)
			)
		)
		(property "Value" "SC1U10V2KX-1GP"
			(at 1.1811 -2.7051 0)
			(unlocked yes)
			(layer "F.Fab")
			(hide yes)
			(effects
				(font
					(size 1.016 1.016)
					(thickness 0.1524)
				)
			)
		)
		(property "Device Type" "C402H22"
			(at 1.1811 -4.2291 0)
			(unlocked yes)
			(layer "F.Fab")
			(hide yes)
			(effects
				(font
					(size 1.016 1.016)
					(thickness 0.1524)
				)
			)
		)
		(duplicate_pad_numbers_are_jumpers no)
		(fp_rect
			(start -0.4318 0.9525)
			(end 0.4318 -0.9525)
			(stroke
				(width 0)
				(type default)
			)
			(fill no)
			(layer "F.CrtYd")
		)
		(fp_rect
			(start -0.4318 0.9525)
			(end 0.4318 -0.9525)
			(stroke
				(width 0)
				(type default)
			)
			(fill no)
			(layer "F.Fab")
		)
		(pad "1" smd custom
			(at 0 -0.4445)
			(size 0.1524 0.1524)
			(layers "F.Cu" "F.Mask" "F.Paste")
			(net "GND")
			(options
				(clearance outline)
				(anchor circle)
			)
			(primitives
				(gr_poly
					(pts
						(arc
							(start 0.3048 -0.2032)
							(mid 0.275042 -0.275042)
							(end 0.2032 -0.3048)
						)
						(arc
							(start -0.2032 -0.3048)
							(mid -0.275042 -0.275042)
							(end -0.3048 -0.2032)
						)
						(arc
							(start -0.3048 0.2032)
							(mid -0.275042 0.275042)
							(end -0.2032 0.3048)
						)
						(arc
							(start 0.2032 0.3048)
							(mid 0.275042 0.275042)
							(end 0.3048 0.2032)
						)
					)
					(width 0)
					(fill yes)
				)
			)
		)
		(pad "2" smd custom
			(at 0 0.4445)
			(size 0.1524 0.1524)
			(layers "F.Cu" "F.Mask" "F.Paste")
			(net "VT235_EN")
			(options
				(clearance outline)
				(anchor circle)
			)
			(primitives
				(gr_poly
					(pts
						(arc
							(start 0.3048 -0.2032)
							(mid 0.275042 -0.275042)
							(end 0.2032 -0.3048)
						)
						(arc
							(start -0.2032 -0.3048)
							(mid -0.275042 -0.275042)
							(end -0.3048 -0.2032)
						)
						(arc
							(start -0.3048 0.2032)
							(mid -0.275042 0.275042)
							(end -0.2032 0.3048)
						)
						(arc
							(start 0.2032 0.3048)
							(mid 0.275042 0.275042)
							(end 0.3048 0.2032)
						)
					)
					(width 0)
					(fill yes)
				)
			)
		)
	)
	(footprint ""
		(layer "F.Cu")
		(at 343.916 -29.464 180)
		(property "Reference" "Q19"
			(at 0 0 180)
			(layer "F.SilkS")
			(hide yes)
			(effects
				(font
					(size 1.27 1.27)
				)
			)
		)
		(property "Value" "2N7002A-7-GP"
			(at 0.127 -8.9662 180)
			(unlocked yes)
			(layer "F.Fab")
			(hide yes)
			(effects
				(font
					(size 1.016 1.016)
					(thickness 0.1524)
				)
			)
		)
		(property "Device Type" "SOT23DGS2D4H48"
			(at 0.127 -10.4902 180)
			(unlocked yes)
			(layer "F.Fab")
			(hide yes)
			(effects
				(font
					(size 1.016 1.016)
					(thickness 0.1524)
				)
			)
		)
		(duplicate_pad_numbers_are_jumpers no)
		(fp_line
			(start 1.651 1.778)
			(end 1.651 -1.778)
			(stroke
				(width 0.1524)
				(type default)
			)
			(layer "F.SilkS")
		)
		(fp_line
			(start 1.651 -1.778)
			(end -1.651 -1.778)
			(stroke
				(width 0.1524)
				(type default)
			)
			(layer "F.SilkS")
		)
		(fp_line
			(start -1.651 1.778)
			(end 1.651 1.778)
			(stroke
				(width 0.1524)
				(type default)
			)
			(layer "F.SilkS")
		)
		(fp_line
			(start -1.651 -1.778)
			(end -1.651 1.778)
			(stroke
				(width 0.1524)
				(type default)
			)
			(layer "F.SilkS")
		)
		(fp_poly
			(pts
				(xy -1.778 1.8796) (xy -1.778 -1.8796) (xy 1.778 -1.8796) (xy 1.778 1.8796)
			)
			(stroke
				(width 0)
				(type default)
			)
			(fill no)
			(layer "F.CrtYd")
		)
		(fp_poly
			(pts
				(xy -1.778 1.8796) (xy -1.778 -1.8796) (xy 1.778 -1.8796) (xy 1.778 1.8796)
			)
			(stroke
				(width 0)
				(type default)
			)
			(fill no)
			(layer "F.Fab")
		)
		(pad "D" smd custom
			(at 0 -0.9525 180)
			(size 0.1905 0.1905)
			(layers "F.Cu" "F.Mask" "F.Paste")
			(net "DEBUG CONSOLE_LED_0")
			(options
				(clearance outline)
				(anchor circle)
			)
			(primitives
				(gr_poly
					(pts
						(arc
							(start -0.1778 0.5715)
							(mid -0.321484 0.511984)
							(end -0.381 0.3683)
						)
						(arc
							(start -0.381 -0.3683)
							(mid -0.321484 -0.511984)
							(end -0.1778 -0.5715)
						)
						(arc
							(start 0.1778 -0.5715)
							(mid 0.321484 -0.511984)
							(end 0.381 -0.3683)
						)
						(arc
							(start 0.381 0.3683)
							(mid 0.321484 0.511984)
							(end 0.1778 0.5715)
						)
					)
					(width 0)
					(fill yes)
				)
			)
		)
		(pad "G" smd custom
			(at -0.98425 0.9525 180)
			(size 0.1905 0.1905)
			(layers "F.Cu" "F.Mask" "F.Paste")
			(net "BMC_CONSOLE_LED0_R")
			(options
				(clearance outline)
				(anchor circle)
			)
			(primitives
				(gr_poly
					(pts
						(arc
							(start -0.1778 0.5715)
							(mid -0.321484 0.511984)
							(end -0.381 0.3683)
						)
						(arc
							(start -0.381 -0.3683)
							(mid -0.321484 -0.511984)
							(end -0.1778 -0.5715)
						)
						(arc
							(start 0.1778 -0.5715)
							(mid 0.321484 -0.511984)
							(end 0.381 -0.3683)
						)
						(arc
							(start 0.381 0.3683)
							(mid 0.321484 0.511984)
							(end 0.1778 0.5715)
						)
					)
					(width 0)
					(fill yes)
				)
			)
		)
		(pad "S" smd custom
			(at 0.98425 0.9525 180)
			(size 0.1905 0.1905)
			(layers "F.Cu" "F.Mask" "F.Paste")
			(net "GND")
			(options
				(clearance outline)
				(anchor circle)
			)
			(primitives
				(gr_poly
					(pts
						(arc
							(start -0.1778 0.5715)
							(mid -0.321484 0.511984)
							(end -0.381 0.3683)
						)
						(arc
							(start -0.381 -0.3683)
							(mid -0.321484 -0.511984)
							(end -0.1778 -0.5715)
						)
						(arc
							(start 0.1778 -0.5715)
							(mid 0.321484 -0.511984)
							(end 0.381 -0.3683)
						)
						(arc
							(start 0.381 0.3683)
							(mid 0.321484 0.511984)
							(end 0.1778 0.5715)
						)
					)
					(width 0)
					(fill yes)
				)
			)
		)
	)
)
